(kicad_pcb
	(version 20260206)
	(generator "pcbnew")
	(generator_version "10.0")
	(general
		(thickness 1.6)
		(legacy_teardrops no)
	)
	(paper "A4")
	(title_block
		(title "Bryce Canyon_F.DPB_16315-1-OCP.brd")
		(comment 1 "Bryce Canyon / footprints 1199-1204 of 2223")
	)
	(layers
		(0 "F.Cu" signal "TOP")
		(4 "In1.Cu" signal "L2GND")
		(6 "In2.Cu" signal "L3")
		(8 "In3.Cu" signal "L4GND")
		(10 "In4.Cu" signal "L5")
		(12 "In5.Cu" signal "L6VCC")
		(14 "In6.Cu" signal "L7VCC")
		(16 "In7.Cu" signal "L8")
		(18 "In8.Cu" signal "L9GND")
		(20 "In9.Cu" signal "L10")
		(22 "In10.Cu" signal "L11GND")
		(2 "B.Cu" signal "BOTTOM")
		(9 "F.Adhes" user "F.Adhesive")
		(11 "B.Adhes" user "B.Adhesive")
		(13 "F.Paste" user "Package Geometry/Pastemask Top")
		(15 "B.Paste" user "Package Geometry/Pastemask Bottom")
		(5 "F.SilkS" user "Ref Des/Silkscreen Top")
		(7 "B.SilkS" user "Ref Des/Silkscreen Bottom")
		(1 "F.Mask" user "Board Geometry/Soldermask Top")
		(3 "B.Mask" user "Board Geometry/Soldermask Bottom")
		(17 "Dwgs.User" user "User.Drawings")
		(19 "Cmts.User" user "User.Comments")
		(21 "Eco1.User" user "User.Eco1")
		(23 "Eco2.User" user "User.Eco2")
		(25 "Edge.Cuts" user "Board Geometry/Outline")
		(27 "Margin" user)
		(31 "F.CrtYd" user "Package Geometry/Place Bound Top")
		(29 "B.CrtYd" user "Package Geometry/Place Bound Bottom")
		(35 "F.Fab" user "Ref Des/Assembly Top")
		(33 "B.Fab" user "Ref Des/Assembly Bottom")
	)
	(footprint ""
		(layer "F.Cu")
		(at 336.804 -62.016894)
		(property "Reference" "Q182"
			(at 0 0 0)
			(layer "F.SilkS")
			(hide yes)
			(effects
				(font
					(size 1.27 1.27)
				)
			)
		)
		(property "Value" "AO4407AL-GP"
			(at -3.707384 -1.5367 0)
			(unlocked yes)
			(layer "F.Fab")
			(hide yes)
			(effects
				(font
					(size 1.016 1.016)
					(thickness 0.1524)
				)
			)
		)
		(property "Device Type" "SOIC8H69"
			(at -3.707384 -3.0607 0)
			(unlocked yes)
			(layer "F.Fab")
			(hide yes)
			(effects
				(font
					(size 1.016 1.016)
					(thickness 0.1524)
				)
			)
		)
		(duplicate_pad_numbers_are_jumpers no)
		(fp_line
			(start -2.7432 -1.4224)
			(end -2.7432 1.4224)
			(stroke
				(width 0.1524)
				(type default)
			)
			(layer "F.SilkS")
		)
		(fp_line
			(start -2.7432 1.4224)
			(end -2.6416 1.4224)
			(stroke
				(width 0.1524)
				(type default)
			)
			(layer "F.SilkS")
		)
		(fp_line
			(start -2.7432 1.4224)
			(end 2.1336 1.4224)
			(stroke
				(width 0.1524)
				(type default)
			)
			(layer "F.SilkS")
		)
		(fp_line
			(start -2.7178 -0.508)
			(end -2.1844 -0.0508)
			(stroke
				(width 0.1524)
				(type default)
			)
			(layer "F.SilkS")
		)
		(fp_line
			(start -2.6289 3.4417)
			(end -2.6289 1.4732)
			(stroke
				(width 0.381)
				(type default)
			)
			(layer "F.SilkS")
		)
		(fp_line
			(start -2.1844 -0.0508)
			(end -2.7178 0.508)
			(stroke
				(width 0.1524)
				(type default)
			)
			(layer "F.SilkS")
		)
		(fp_line
			(start 2.1336 -1.4224)
			(end -2.7432 -1.4224)
			(stroke
				(width 0.1524)
				(type default)
			)
			(layer "F.SilkS")
		)
		(fp_line
			(start 2.1336 1.4224)
			(end 2.1336 -1.4224)
			(stroke
				(width 0.1524)
				(type default)
			)
			(layer "F.SilkS")
		)
		(fp_poly
			(pts
				(xy -2.2098 -1.4224) (xy -2.2098 1.4224) (xy 2.2098 1.4224) (xy 2.2098 -1.4224)
			)
			(stroke
				(width 0)
				(type default)
			)
			(fill yes)
			(layer "F.SilkS")
		)
		(fp_rect
			(start -2.450084 2.999994)
			(end 2.450084 -2.999994)
			(stroke
				(width 0)
				(type default)
			)
			(fill no)
			(layer "F.CrtYd")
		)
		(fp_poly
			(pts
				(xy -2.8194 3.6322) (xy -2.8194 -3.6322) (xy 2.8194 -3.6322) (xy 2.8194 1.18364) (xy 2.450084 1.18364)
				(xy 2.450084 -2.999994) (xy -2.450084 -2.999994) (xy -2.450084 2.999994) (xy 2.450084 2.999994)
				(xy 2.450084 1.18618) (xy 2.8194 1.18618) (xy 2.8194 3.6322)
			)
			(stroke
				(width 0)
				(type default)
			)
			(fill no)
			(layer "F.CrtYd")
		)
		(fp_rect
			(start -2.8194 3.6322)
			(end 2.8194 -3.6322)
			(stroke
				(width 0)
				(type default)
			)
			(fill no)
			(layer "F.Fab")
		)
		(pad "1" smd rect
			(at -1.905 2.54)
			(size 0.635 1.651)
			(layers "F.Cu" "F.Mask" "F.Paste")
			(net "P12V_A")
		)
		(pad "2" smd rect
			(at -0.635 2.54)
			(size 0.635 1.651)
			(layers "F.Cu" "F.Mask" "F.Paste")
			(net "P12V_A")
		)
		(pad "3" smd rect
			(at 0.635 2.54)
			(size 0.635 1.651)
			(layers "F.Cu" "F.Mask" "F.Paste")
			(net "P12V_A")
		)
		(pad "4" smd rect
			(at 1.905 2.54)
			(size 0.635 1.651)
			(layers "F.Cu" "F.Mask" "F.Paste")
			(net "SW_HDD_N30")
		)
		(pad "5" smd rect
			(at 1.905 -2.54)
			(size 0.635 1.651)
			(layers "F.Cu" "F.Mask" "F.Paste")
			(net "P12V_HDD30")
		)
		(pad "6" smd rect
			(at 0.635 -2.54)
			(size 0.635 1.651)
			(layers "F.Cu" "F.Mask" "F.Paste")
			(net "P12V_HDD30")
		)
		(pad "7" smd rect
			(at -0.635 -2.54)
			(size 0.635 1.651)
			(layers "F.Cu" "F.Mask" "F.Paste")
			(net "P12V_HDD30")
		)
		(pad "8" smd rect
			(at -1.905 -2.54)
			(size 0.635 1.651)
			(layers "F.Cu" "F.Mask" "F.Paste")
			(net "P12V_HDD30")
		)
	)
	(footprint ""
		(layer "F.Cu")
		(at 116.121942 -272.726404)
		(property "Reference" "R212"
			(at 0 0 0)
			(layer "F.SilkS")
			(hide yes)
			(effects
				(font
					(size 1.27 1.27)
				)
			)
		)
		(property "Value" "4K7R2J-2-GP"
			(at 0.064008 -3.993896 0)
			(unlocked yes)
			(layer "F.Fab")
			(hide yes)
			(effects
				(font
					(size 1.016 1.016)
					(thickness 0.1524)
				)
			)
		)
		(property "Device Type" "R402H16"
			(at 0.064008 -5.517896 0)
			(unlocked yes)
			(layer "F.Fab")
			(hide yes)
			(effects
				(font
					(size 1.016 1.016)
					(thickness 0.1524)
				)
			)
		)
		(duplicate_pad_numbers_are_jumpers no)
		(fp_line
			(start -0.508 -0.9398)
			(end -0.508 0.9398)
			(stroke
				(width 0.1524)
				(type default)
			)
			(layer "F.SilkS")
		)
		(fp_line
			(start 0.508 -0.9398)
			(end -0.508 -0.9398)
			(stroke
				(width 0.1524)
				(type default)
			)
			(layer "F.SilkS")
		)
		(fp_rect
			(start -0.508 0.9398)
			(end 0.508 -0.9398)
			(stroke
				(width 0)
				(type default)
			)
			(fill no)
			(layer "F.CrtYd")
		)
		(fp_rect
			(start -0.508 0.9398)
			(end 0.508 -0.9398)
			(stroke
				(width 0)
				(type default)
			)
			(fill no)
			(layer "F.Fab")
		)
		(pad "1" smd custom
			(at 0 -0.4445)
			(size 0.1397 0.1397)
			(layers "F.Cu" "F.Mask" "F.Paste")
			(net "SW_PWR_R_HDD3")
			(options
				(clearance outline)
				(anchor circle)
			)
			(primitives
				(gr_poly
					(pts
						(arc
							(start -0.1778 -0.2794)
							(mid -0.249642 -0.249642)
							(end -0.2794 -0.1778)
						)
						(arc
							(start -0.2794 0.1778)
							(mid -0.249642 0.249642)
							(end -0.1778 0.2794)
						)
						(arc
							(start 0.1778 0.2794)
							(mid 0.249642 0.249642)
							(end 0.2794 0.1778)
						)
						(arc
							(start 0.2794 -0.1778)
							(mid 0.249642 -0.249642)
							(end 0.1778 -0.2794)
						)
					)
					(width 0)
					(fill yes)
				)
			)
		)
		(pad "2" smd custom
			(at 0 0.4445)
			(size 0.1397 0.1397)
			(layers "F.Cu" "F.Mask" "F.Paste")
			(net "GND")
			(options
				(clearance outline)
				(anchor circle)
			)
			(primitives
				(gr_poly
					(pts
						(arc
							(start -0.1778 -0.2794)
							(mid -0.249642 -0.249642)
							(end -0.2794 -0.1778)
						)
						(arc
							(start -0.2794 0.1778)
							(mid -0.249642 0.249642)
							(end -0.1778 0.2794)
						)
						(arc
							(start 0.1778 0.2794)
							(mid 0.249642 0.249642)
							(end 0.2794 0.1778)
						)
						(arc
							(start 0.2794 -0.1778)
							(mid 0.249642 -0.249642)
							(end 0.1778 -0.2794)
						)
					)
					(width 0)
					(fill yes)
				)
			)
		)
	)
	(footprint ""
		(layer "F.Cu")
		(at 415.909252 -292.169342 90)
		(property "Reference" "R337"
			(at 0 0 90)
			(layer "F.SilkS")
			(hide yes)
			(effects
				(font
					(size 1.27 1.27)
				)
			)
		)
		(property "Value" "10KR2F-2-GP"
			(at 0.064008 -3.993896 90)
			(unlocked yes)
			(layer "F.Fab")
			(hide yes)
			(effects
				(font
					(size 1.016 1.016)
					(thickness 0.1524)
				)
			)
		)
		(property "Device Type" "R402H16"
			(at 0.064008 -5.517896 90)
			(unlocked yes)
			(layer "F.Fab")
			(hide yes)
			(effects
				(font
					(size 1.016 1.016)
					(thickness 0.1524)
				)
			)
		)
		(duplicate_pad_numbers_are_jumpers no)
		(fp_line
			(start 0.508 -0.9398)
			(end -0.508 -0.9398)
			(stroke
				(width 0.1524)
				(type default)
			)
			(layer "F.SilkS")
		)
		(fp_line
			(start -0.508 -0.9398)
			(end -0.508 0.9398)
			(stroke
				(width 0.1524)
				(type default)
			)
			(layer "F.SilkS")
		)
		(fp_rect
			(start -0.508 0.9398)
			(end 0.508 -0.9398)
			(stroke
				(width 0)
				(type default)
			)
			(fill no)
			(layer "F.CrtYd")
		)
		(fp_rect
			(start -0.508 0.9398)
			(end 0.508 -0.9398)
			(stroke
				(width 0)
				(type default)
			)
			(fill no)
			(layer "F.Fab")
		)
		(pad "1" smd custom
			(at 0 -0.4445 90)
			(size 0.1397 0.1397)
			(layers "F.Cu" "F.Mask" "F.Paste")
			(net "P3V3_STBY_A")
			(options
				(clearance outline)
				(anchor circle)
			)
			(primitives
				(gr_poly
					(pts
						(arc
							(start -0.1778 -0.2794)
							(mid -0.249642 -0.249642)
							(end -0.2794 -0.1778)
						)
						(arc
							(start -0.2794 0.1778)
							(mid -0.249642 0.249642)
							(end -0.1778 0.2794)
						)
						(arc
							(start 0.1778 0.2794)
							(mid 0.249642 0.249642)
							(end 0.2794 0.1778)
						)
						(arc
							(start 0.2794 -0.1778)
							(mid 0.249642 -0.249642)
							(end 0.1778 -0.2794)
						)
					)
					(width 0)
					(fill yes)
				)
			)
		)
		(pad "2" smd custom
			(at 0 0.4445 90)
			(size 0.1397 0.1397)
			(layers "F.Cu" "F.Mask" "F.Paste")
			(net "HDD_PRSNT_9")
			(options
				(clearance outline)
				(anchor circle)
			)
			(primitives
				(gr_poly
					(pts
						(arc
							(start -0.1778 -0.2794)
							(mid -0.249642 -0.249642)
							(end -0.2794 -0.1778)
						)
						(arc
							(start -0.2794 0.1778)
							(mid -0.249642 0.249642)
							(end -0.1778 0.2794)
						)
						(arc
							(start 0.1778 0.2794)
							(mid 0.249642 0.249642)
							(end 0.2794 0.1778)
						)
						(arc
							(start 0.2794 -0.1778)
							(mid 0.249642 -0.249642)
							(end 0.1778 -0.2794)
						)
					)
					(width 0)
					(fill yes)
				)
			)
		)
	)
	(footprint ""
		(layer "F.Cu")
		(at 431.962052 -47.792894 90)
		(property "Reference" "D33"
			(at 0 0 90)
			(layer "F.SilkS")
			(hide yes)
			(effects
				(font
					(size 1.27 1.27)
				)
			)
		)
		(property "Value" "RB551V30-GP"
			(at 0 -6.7818 90)
			(unlocked yes)
			(layer "F.Fab")
			(hide yes)
			(effects
				(font
					(size 1.016 1.016)
					(thickness 0.1524)
				)
			)
		)
		(property "Device Type" "SOD323AKH38"
			(at 0 -8.6868 90)
			(unlocked yes)
			(layer "F.Fab")
			(hide yes)
			(effects
				(font
					(size 1.016 1.016)
					(thickness 0.1524)
				)
			)
		)
		(duplicate_pad_numbers_are_jumpers no)
		(fp_line
			(start 0.889 -1.9304)
			(end 0.889 2.159)
			(stroke
				(width 0.1524)
				(type default)
			)
			(layer "F.SilkS")
		)
		(fp_line
			(start -0.889 -1.9304)
			(end 0.889 -1.9304)
			(stroke
				(width 0.1524)
				(type default)
			)
			(layer "F.SilkS")
		)
		(fp_line
			(start 0.762 2.0574)
			(end -0.762 2.0574)
			(stroke
				(width 0.508)
				(type default)
			)
			(layer "F.SilkS")
		)
		(fp_line
			(start 0.889 2.159)
			(end -0.889 2.159)
			(stroke
				(width 0.1524)
				(type default)
			)
			(layer "F.SilkS")
		)
		(fp_line
			(start -0.889 2.159)
			(end -0.889 -1.9304)
			(stroke
				(width 0.1524)
				(type default)
			)
			(layer "F.SilkS")
		)
		(fp_rect
			(start -1.016 2.3114)
			(end 1.016 -2.0066)
			(stroke
				(width 0)
				(type default)
			)
			(fill no)
			(layer "F.CrtYd")
		)
		(fp_poly
			(pts
				(xy -1.016 -2.0066) (xy 1.016 -2.0066) (xy 1.016 2.3114) (xy -1.016 2.3114)
			)
			(stroke
				(width 0)
				(type default)
			)
			(fill no)
			(layer "F.Fab")
		)
		(pad "A" smd rect
			(at 0 -1.143 90)
			(size 0.5588 1.016)
			(layers "F.Cu" "F.Mask" "F.Paste")
			(net "SW_HDD_R33")
		)
		(pad "K" smd rect
			(at 0 1.143 90)
			(size 0.5588 1.016)
			(layers "F.Cu" "F.Mask" "F.Paste")
			(net "SW_HDD_N33")
		)
	)
	(footprint ""
		(layer "F.Cu")
		(at 223.500442 -212.700362)
		(property "Reference" "U16"
			(at 0 0 0)
			(layer "F.SilkS")
			(hide yes)
			(effects
				(font
					(size 1.27 1.27)
				)
			)
		)
		(property "Value" "PCA9511ADP-T-GP"
			(at 0 -13.1572 0)
			(unlocked yes)
			(layer "F.Fab")
			(hide yes)
			(effects
				(font
					(size 1.016 1.016)
					(thickness 0.1524)
				)
			)
		)
		(property "Device Type" "SSOIC8-2H44"
			(at 0 -15.1892 0)
			(unlocked yes)
			(layer "F.Fab")
			(hide yes)
			(effects
				(font
					(size 1.016 1.016)
					(thickness 0.1524)
				)
			)
		)
		(duplicate_pad_numbers_are_jumpers no)
		(fp_line
			(start -1.9304 -1.016)
			(end 1.0922 -1.016)
			(stroke
				(width 0.1524)
				(type default)
			)
			(layer "F.SilkS")
		)
		(fp_line
			(start -1.9304 1.016)
			(end -1.9304 -1.016)
			(stroke
				(width 0.1524)
				(type default)
			)
			(layer "F.SilkS")
		)
		(fp_line
			(start -1.7018 1.0414)
			(end -1.7018 2.9718)
			(stroke
				(width 0.635)
				(type default)
			)
			(layer "F.SilkS")
		)
		(fp_line
			(start -1.524 0)
			(end -1.9304 -0.4064)
			(stroke
				(width 0.1524)
				(type default)
			)
			(layer "F.SilkS")
		)
		(fp_line
			(start -1.524 0)
			(end -1.9304 0.4064)
			(stroke
				(width 0.1524)
				(type default)
			)
			(layer "F.SilkS")
		)
		(fp_line
			(start 1.0922 -1.016)
			(end 1.0922 1.016)
			(stroke
				(width 0.1524)
				(type default)
			)
			(layer "F.SilkS")
		)
		(fp_line
			(start 1.0922 1.016)
			(end -1.9304 1.016)
			(stroke
				(width 0.1524)
				(type default)
			)
			(layer "F.SilkS")
		)
		(fp_poly
			(pts
				(xy -1.1938 -1.016) (xy 1.0922 -1.016) (xy 1.0922 1.016) (xy -1.1938 1.016)
			)
			(stroke
				(width 0)
				(type default)
			)
			(fill yes)
			(layer "F.SilkS")
		)
		(fp_rect
			(start -2.0066 3.3401)
			(end 2.0066 -3.3401)
			(stroke
				(width 0)
				(type default)
			)
			(fill no)
			(layer "F.CrtYd")
		)
		(fp_poly
			(pts
				(xy -2.0066 -3.3401) (xy 2.0066 -3.3401) (xy 2.0066 3.3401) (xy -2.0066 3.3401)
			)
			(stroke
				(width 0)
				(type default)
			)
			(fill no)
			(layer "F.Fab")
		)
		(pad "1" smd rect
			(at -0.97536 2.0701)
			(size 0.4064 1.524)
			(layers "F.Cu" "F.Mask" "F.Paste")
			(net "I2C_SCC_BUFF_EN")
		)
		(pad "2" smd rect
			(at -0.32512 2.0701)
			(size 0.4064 1.524)
			(layers "F.Cu" "F.Mask" "F.Paste")
			(net "I2C_SCC_A_SCL_BUF")
		)
		(pad "3" smd rect
			(at 0.32512 2.0701)
			(size 0.4064 1.524)
			(layers "F.Cu" "F.Mask" "F.Paste")
			(net "I2C_SCC_A_SCL")
		)
		(pad "4" smd rect
			(at 0.97536 2.0701)
			(size 0.4064 1.524)
			(layers "F.Cu" "F.Mask" "F.Paste")
			(net "GND")
		)
		(pad "5" smd rect
			(at 0.97536 -2.0701)
			(size 0.4064 1.524)
			(layers "F.Cu" "F.Mask" "F.Paste")
			(net "I2C_SCC_BUFF_READY")
		)
		(pad "6" smd rect
			(at 0.32512 -2.0701)
			(size 0.4064 1.524)
			(layers "F.Cu" "F.Mask" "F.Paste")
			(net "I2C_SCC_A_SDA")
		)
		(pad "7" smd rect
			(at -0.32512 -2.0701)
			(size 0.4064 1.524)
			(layers "F.Cu" "F.Mask" "F.Paste")
			(net "I2C_SCC_A_SDA_BUF")
		)
		(pad "8" smd rect
			(at -0.97536 -2.0701)
			(size 0.4064 1.524)
			(layers "F.Cu" "F.Mask" "F.Paste")
			(net "P3V3_STBY_A")
		)
	)
	(footprint ""
		(layer "F.Cu")
		(at 336.804 -177.016918)
		(property "Reference" "Q110"
			(at 0 0 0)
			(layer "F.SilkS")
			(hide yes)
			(effects
				(font
					(size 1.27 1.27)
				)
			)
		)
		(property "Value" "AO4407AL-GP"
			(at -3.707384 -1.5367 0)
			(unlocked yes)
			(layer "F.Fab")
			(hide yes)
			(effects
				(font
					(size 1.016 1.016)
					(thickness 0.1524)
				)
			)
		)
		(property "Device Type" "SOIC8H69"
			(at -3.707384 -3.0607 0)
			(unlocked yes)
			(layer "F.Fab")
			(hide yes)
			(effects
				(font
					(size 1.016 1.016)
					(thickness 0.1524)
				)
			)
		)
		(duplicate_pad_numbers_are_jumpers no)
		(fp_line
			(start -2.7432 -1.4224)
			(end -2.7432 1.4224)
			(stroke
				(width 0.1524)
				(type default)
			)
			(layer "F.SilkS")
		)
		(fp_line
			(start -2.7432 1.4224)
			(end -2.6416 1.4224)
			(stroke
				(width 0.1524)
				(type default)
			)
			(layer "F.SilkS")
		)
		(fp_line
			(start -2.7432 1.4224)
			(end 2.1336 1.4224)
			(stroke
				(width 0.1524)
				(type default)
			)
			(layer "F.SilkS")
		)
		(fp_line
			(start -2.7178 -0.508)
			(end -2.1844 -0.0508)
			(stroke
				(width 0.1524)
				(type default)
			)
			(layer "F.SilkS")
		)
		(fp_line
			(start -2.6289 3.4417)
			(end -2.6289 1.4732)
			(stroke
				(width 0.381)
				(type default)
			)
			(layer "F.SilkS")
		)
		(fp_line
			(start -2.1844 -0.0508)
			(end -2.7178 0.508)
			(stroke
				(width 0.1524)
				(type default)
			)
			(layer "F.SilkS")
		)
		(fp_line
			(start 2.1336 -1.4224)
			(end -2.7432 -1.4224)
			(stroke
				(width 0.1524)
				(type default)
			)
			(layer "F.SilkS")
		)
		(fp_line
			(start 2.1336 1.4224)
			(end 2.1336 -1.4224)
			(stroke
				(width 0.1524)
				(type default)
			)
			(layer "F.SilkS")
		)
		(fp_poly
			(pts
				(xy -2.2098 -1.4224) (xy -2.2098 1.4224) (xy 2.2098 1.4224) (xy 2.2098 -1.4224)
			)
			(stroke
				(width 0)
				(type default)
			)
			(fill yes)
			(layer "F.SilkS")
		)
		(fp_rect
			(start -2.450084 2.999994)
			(end 2.450084 -2.999994)
			(stroke
				(width 0)
				(type default)
			)
			(fill no)
			(layer "F.CrtYd")
		)
		(fp_poly
			(pts
				(xy -2.8194 3.6322) (xy -2.8194 -3.6322) (xy 2.8194 -3.6322) (xy 2.8194 1.18364) (xy 2.450084 1.18364)
				(xy 2.450084 -2.999994) (xy -2.450084 -2.999994) (xy -2.450084 2.999994) (xy 2.450084 2.999994)
				(xy 2.450084 1.18618) (xy 2.8194 1.18618) (xy 2.8194 3.6322)
			)
			(stroke
				(width 0)
				(type default)
			)
			(fill no)
			(layer "F.CrtYd")
		)
		(fp_rect
			(start -2.8194 3.6322)
			(end 2.8194 -3.6322)
			(stroke
				(width 0)
				(type default)
			)
			(fill no)
			(layer "F.Fab")
		)
		(pad "1" smd rect
			(at -1.905 2.54)
			(size 0.635 1.651)
			(layers "F.Cu" "F.Mask" "F.Paste")
			(net "P12V_A")
		)
		(pad "2" smd rect
			(at -0.635 2.54)
			(size 0.635 1.651)
			(layers "F.Cu" "F.Mask" "F.Paste")
			(net "P12V_A")
		)
		(pad "3" smd rect
			(at 0.635 2.54)
			(size 0.635 1.651)
			(layers "F.Cu" "F.Mask" "F.Paste")
			(net "P12V_A")
		)
		(pad "4" smd rect
			(at 1.905 2.54)
			(size 0.635 1.651)
			(layers "F.Cu" "F.Mask" "F.Paste")
			(net "SW_HDD_N18")
		)
		(pad "5" smd rect
			(at 1.905 -2.54)
			(size 0.635 1.651)
			(layers "F.Cu" "F.Mask" "F.Paste")
			(net "P12V_HDD18")
		)
		(pad "6" smd rect
			(at 0.635 -2.54)
			(size 0.635 1.651)
			(layers "F.Cu" "F.Mask" "F.Paste")
			(net "P12V_HDD18")
		)
		(pad "7" smd rect
			(at -0.635 -2.54)
			(size 0.635 1.651)
			(layers "F.Cu" "F.Mask" "F.Paste")
			(net "P12V_HDD18")
		)
		(pad "8" smd rect
			(at -1.905 -2.54)
			(size 0.635 1.651)
			(layers "F.Cu" "F.Mask" "F.Paste")
			(net "P12V_HDD18")
		)
	)
)
